(kicad_pcb
	(version 20241229)
	(generator "pcbnew")
	(generator_version "9.0")
	(general
		(thickness 1.294)
		(legacy_teardrops no)
	)
	(paper "A3")
	(title_block
		(title "Kintex 410T devboard")
		(date "2024-04-03")
		(rev "1.1.2")
		(comment 9 "footprint 89 of 975 (J18), pads 359-446 of 564")
	)
	(layers
		(0 "F.Cu" mixed)
		(4 "In1.Cu" power)
		(6 "In2.Cu" power)
		(8 "In3.Cu" mixed)
		(10 "In4.Cu" power)
		(12 "In5.Cu" mixed)
		(14 "In6.Cu" power)
		(16 "In7.Cu" mixed)
		(18 "In8.Cu" power)
		(2 "B.Cu" mixed)
		(9 "F.Adhes" user "F.Adhesive")
		(11 "B.Adhes" user "B.Adhesive")
		(13 "F.Paste" user)
		(15 "B.Paste" user)
		(5 "F.SilkS" user "F.Silkscreen")
		(7 "B.SilkS" user "B.Silkscreen")
		(1 "F.Mask" user)
		(3 "B.Mask" user)
		(17 "Dwgs.User" user "User.Drawings")
		(19 "Cmts.User" user "User.Comments")
		(21 "Eco1.User" user "User.Eco1")
		(23 "Eco2.User" user "User.Eco2")
		(25 "Edge.Cuts" user)
		(27 "Margin" user)
		(31 "F.CrtYd" user "F.Courtyard")
		(29 "B.CrtYd" user "B.Courtyard")
		(35 "F.Fab" user)
		(33 "B.Fab" user)
	)
	(footprint "antmicro-footprints:ASP-184329-01_mounting_holes"
		(layer "F.Cu")
		(at 162.000001 106.000001 90)
		(property "Reference" "J18"
			(at 28.280001 4.299999 180)
			(layer "F.SilkS")
			(effects
				(font
					(size 0.7 0.7)
					(thickness 0.15)
				)
				(justify left bottom)
			)
		)
		(property "Value" "ASP-184329-01_mounting_holes"
			(at -8.4 0.2 90)
			(layer "F.Fab")
			(effects
				(font
					(size 0.7 0.7)
					(thickness 0.15)
				)
				(justify left bottom)
			)
		)
		(property "Description" "Mezzanine Connector, Array, Female, 1.27 mm, 14 Rows, 560 Contacts, Surface Mount"
			(at 0 0 90)
			(layer "F.Fab")
			(hide yes)
			(effects
				(font
					(size 1.27 1.27)
					(thickness 0.15)
				)
			)
		)
		(property "Author" "Antmicro"
			(at 268.000002 -56 0)
			(layer "F.Fab")
			(hide yes)
			(effects
				(font
					(size 1 1)
					(thickness 0.15)
				)
			)
		)
		(property "License" "Apache-2.0"
			(at 268.000002 -56 0)
			(layer "F.Fab")
			(hide yes)
			(effects
				(font
					(size 1 1)
					(thickness 0.15)
				)
			)
		)
		(property "MPN" "ASP-184329-01"
			(at 268.000002 -56 0)
			(layer "F.Fab")
			(hide yes)
			(effects
				(font
					(size 1 1)
					(thickness 0.15)
				)
			)
		)
		(property "Manufacturer" "Samtec"
			(at 268.000002 -56 0)
			(layer "F.Fab")
			(hide yes)
			(effects
				(font
					(size 1 1)
					(thickness 0.15)
				)
			)
		)
		(sheetname "FMC+ HSPC")
		(sheetfile "fmc-hspc.kicad_sch")
		(attr smd)
		(pad "J35" smd circle
			(at -18.415 -4.446 90)
			(size 0.64 0.64)
			(layers "F.Cu" "F.Mask")
			(net 1 "GND")
			(pinfunction "GND")
			(pintype "passive")
		)
		(pad "J36" smd circle
			(at -19.685 -4.446 90)
			(size 0.64 0.64)
			(layers "F.Cu" "F.Mask")
			(net 213 "unconnected-(J18E-HB18_P-PadJ36)")
			(pinfunction "HB18_P")
			(pintype "passive+no_connect")
		)
		(pad "J37" smd circle
			(at -20.956 -4.446 90)
			(size 0.64 0.64)
			(layers "F.Cu" "F.Mask")
			(net 214 "unconnected-(J18E-HB18_N-PadJ37)")
			(pinfunction "HB18_N")
			(pintype "passive+no_connect")
		)
		(pad "J38" smd circle
			(at -22.226 -4.446 90)
			(size 0.64 0.64)
			(layers "F.Cu" "F.Mask")
			(net 1 "GND")
			(pinfunction "GND")
			(pintype "passive")
		)
		(pad "J39" smd circle
			(at -23.497 -4.446 90)
			(size 0.64 0.64)
			(layers "F.Cu" "F.Mask")
			(net 215 "unconnected-(J18A-VIO_B_M2C-PadJ39)")
			(pinfunction "VIO_B_M2C")
			(pintype "passive+no_connect")
		)
		(pad "J40" smd circle
			(at -24.767 -4.446 90)
			(size 0.64 0.64)
			(layers "F.Cu" "F.Mask")
			(net 1 "GND")
			(pinfunction "GND")
			(pintype "passive")
		)
		(pad "K01" smd circle
			(at 24.765 -5.715 90)
			(size 0.64 0.64)
			(layers "F.Cu" "F.Mask")
			(net 216 "Net-(J18A-VREF_B_M2C)")
			(pinfunction "VREF_B_M2C")
			(pintype "passive")
		)
		(pad "K02" smd circle
			(at 23.495 -5.715 90)
			(size 0.64 0.64)
			(layers "F.Cu" "F.Mask")
			(net 1 "GND")
			(pinfunction "GND")
			(pintype "passive")
		)
		(pad "K03" smd circle
			(at 22.225 -5.715 90)
			(size 0.64 0.64)
			(layers "F.Cu" "F.Mask")
			(net 1 "GND")
			(pinfunction "GND")
			(pintype "passive")
		)
		(pad "K04" smd circle
			(at 20.954 -5.715 90)
			(size 0.64 0.64)
			(layers "F.Cu" "F.Mask")
			(net 593 "/FMC+ HSPC/GTR_REFCLK2_R_P")
			(pinfunction "CLK2_BIDIR_P")
			(pintype "passive")
		)
		(pad "K05" smd circle
			(at 19.684 -5.715 90)
			(size 0.64 0.64)
			(layers "F.Cu" "F.Mask")
			(net 595 "/FMC+ HSPC/GTR_REFCLK2_R_N")
			(pinfunction "CLK2_BIDIR_N")
			(pintype "passive")
		)
		(pad "K06" smd circle
			(at 18.414 -5.715 90)
			(size 0.64 0.64)
			(layers "F.Cu" "F.Mask")
			(net 1 "GND")
			(pinfunction "GND")
			(pintype "passive")
		)
		(pad "K07" smd circle
			(at 17.144 -5.715 90)
			(size 0.64 0.64)
			(layers "F.Cu" "F.Mask")
			(net 278 "/FMC+ HSPC/FMC.IO16_P")
			(pinfunction "HA02_P")
			(pintype "passive")
		)
		(pad "K08" smd circle
			(at 15.874 -5.715 90)
			(size 0.64 0.64)
			(layers "F.Cu" "F.Mask")
			(net 268 "/FMC+ HSPC/FMC.IO16_N")
			(pinfunction "HA02_N")
			(pintype "passive")
		)
		(pad "K09" smd circle
			(at 14.605 -5.715 90)
			(size 0.64 0.64)
			(layers "F.Cu" "F.Mask")
			(net 1 "GND")
			(pinfunction "GND")
			(pintype "passive")
		)
		(pad "K10" smd circle
			(at 13.335 -5.715 90)
			(size 0.64 0.64)
			(layers "F.Cu" "F.Mask")
			(net 239 "/FMC+ HSPC/FMC.IO21_P")
			(pinfunction "HA06_P")
			(pintype "passive")
		)
		(pad "K11" smd circle
			(at 12.063 -5.715 90)
			(size 0.64 0.64)
			(layers "F.Cu" "F.Mask")
			(net 437 "/FMC+ HSPC/FMC.IO21_N")
			(pinfunction "HA06_N")
			(pintype "passive")
		)
		(pad "K12" smd circle
			(at 10.794 -5.715 90)
			(size 0.64 0.64)
			(layers "F.Cu" "F.Mask")
			(net 1 "GND")
			(pinfunction "GND")
			(pintype "passive")
		)
		(pad "K13" smd circle
			(at 9.525 -5.715 90)
			(size 0.64 0.64)
			(layers "F.Cu" "F.Mask")
			(net 217 "unconnected-(J18D-HA10_P-PadK13)")
			(pinfunction "HA10_P")
			(pintype "passive+no_connect")
		)
		(pad "K14" smd circle
			(at 8.255 -5.715 90)
			(size 0.64 0.64)
			(layers "F.Cu" "F.Mask")
			(net 218 "unconnected-(J18D-HA10_N-PadK14)")
			(pinfunction "HA10_N")
			(pintype "passive+no_connect")
		)
		(pad "K15" smd circle
			(at 6.985 -5.715 90)
			(size 0.64 0.64)
			(layers "F.Cu" "F.Mask")
			(net 1 "GND")
			(pinfunction "GND")
			(pintype "passive")
		)
		(pad "K16" smd circle
			(at 5.714 -5.715 90)
			(size 0.64 0.64)
			(layers "F.Cu" "F.Mask")
			(net 428 "/FMC+ HSPC/FMC.IO17_P")
			(pinfunction "HA17_P_CC")
			(pintype "passive")
		)
		(pad "K17" smd circle
			(at 4.445 -5.715 90)
			(size 0.64 0.64)
			(layers "F.Cu" "F.Mask")
			(net 426 "/FMC+ HSPC/FMC.IO17_N")
			(pinfunction "HA17_N_CC")
			(pintype "passive")
		)
		(pad "K18" smd circle
			(at 3.173 -5.715 90)
			(size 0.64 0.64)
			(layers "F.Cu" "F.Mask")
			(net 1 "GND")
			(pinfunction "GND")
			(pintype "passive")
		)
		(pad "K19" smd circle
			(at 1.904 -5.715 90)
			(size 0.64 0.64)
			(layers "F.Cu" "F.Mask")
			(net 424 "/FMC+ HSPC/FMC.IO13_P")
			(pinfunction "HA21_P")
			(pintype "passive")
		)
		(pad "K20" smd circle
			(at 0.633 -5.715 90)
			(size 0.64 0.64)
			(layers "F.Cu" "F.Mask")
			(net 423 "/FMC+ HSPC/FMC.IO13_N")
			(pinfunction "HA21_N")
			(pintype "passive")
		)
		(pad "K21" smd circle
			(at -0.635 -5.715 90)
			(size 0.64 0.64)
			(layers "F.Cu" "F.Mask")
			(net 1 "GND")
			(pinfunction "GND")
			(pintype "passive")
		)
		(pad "K22" smd circle
			(at -1.905 -5.715 90)
			(size 0.64 0.64)
			(layers "F.Cu" "F.Mask")
			(net 340 "/FMC+ HSPC/FMC.IO11_P")
			(pinfunction "HA23_P")
			(pintype "passive")
		)
		(pad "K23" smd circle
			(at -3.176 -5.715 90)
			(size 0.64 0.64)
			(layers "F.Cu" "F.Mask")
			(net 339 "/FMC+ HSPC/FMC.IO11_N")
			(pinfunction "HA23_N")
			(pintype "passive")
		)
		(pad "K24" smd circle
			(at -4.446 -5.715 90)
			(size 0.64 0.64)
			(layers "F.Cu" "F.Mask")
			(net 1 "GND")
			(pinfunction "GND")
			(pintype "passive")
		)
		(pad "K25" smd circle
			(at -5.715 -5.715 90)
			(size 0.64 0.64)
			(layers "F.Cu" "F.Mask")
			(net 337 "/FMC+ HSPC/FMC.IO20_P")
			(pinfunction "HB00_P_CC")
			(pintype "passive")
		)
		(pad "K26" smd circle
			(at -6.986 -5.715 90)
			(size 0.64 0.64)
			(layers "F.Cu" "F.Mask")
			(net 335 "/FMC+ HSPC/FMC.IO20_N")
			(pinfunction "HB00_N_CC")
			(pintype "passive")
		)
		(pad "K27" smd circle
			(at -8.257 -5.715 90)
			(size 0.64 0.64)
			(layers "F.Cu" "F.Mask")
			(net 1 "GND")
			(pinfunction "GND")
			(pintype "passive")
		)
		(pad "K28" smd circle
			(at -9.526 -5.715 90)
			(size 0.64 0.64)
			(layers "F.Cu" "F.Mask")
			(net 334 "/FMC+ HSPC/FMC.IO25")
			(pinfunction "HB06_P_CC")
			(pintype "passive")
		)
		(pad "K29" smd circle
			(at -10.795 -5.715 90)
			(size 0.64 0.64)
			(layers "F.Cu" "F.Mask")
			(net 219 "unconnected-(J18E-HB06_N_CC-PadK29)")
			(pinfunction "HB06_N_CC")
			(pintype "passive+no_connect")
		)
		(pad "K30" smd circle
			(at -12.065 -5.715 90)
			(size 0.64 0.64)
			(layers "F.Cu" "F.Mask")
			(net 1 "GND")
			(pinfunction "GND")
			(pintype "passive")
		)
		(pad "K31" smd circle
			(at -13.337 -5.715 90)
			(size 0.64 0.64)
			(layers "F.Cu" "F.Mask")
			(net 221 "unconnected-(J18E-HB10_P-PadK31)")
			(pinfunction "HB10_P")
			(pintype "passive+no_connect")
		)
		(pad "K32" smd circle
			(at -14.606 -5.715 90)
			(size 0.64 0.64)
			(layers "F.Cu" "F.Mask")
			(net 222 "unconnected-(J18E-HB10_N-PadK32)")
			(pinfunction "HB10_N")
			(pintype "passive+no_connect")
		)
		(pad "K33" smd circle
			(at -15.875 -5.715 90)
			(size 0.64 0.64)
			(layers "F.Cu" "F.Mask")
			(net 1 "GND")
			(pinfunction "GND")
			(pintype "passive")
		)
		(pad "K34" smd circle
			(at -17.145 -5.715 90)
			(size 0.64 0.64)
			(layers "F.Cu" "F.Mask")
			(net 223 "unconnected-(J18E-HB14_P-PadK34)")
			(pinfunction "HB14_P")
			(pintype "passive+no_connect")
		)
		(pad "K35" smd circle
			(at -18.415 -5.715 90)
			(size 0.64 0.64)
			(layers "F.Cu" "F.Mask")
			(net 224 "unconnected-(J18E-HB14_N-PadK35)")
			(pinfunction "HB14_N")
			(pintype "passive+no_connect")
		)
		(pad "K36" smd circle
			(at -19.685 -5.715 90)
			(size 0.64 0.64)
			(layers "F.Cu" "F.Mask")
			(net 1 "GND")
			(pinfunction "GND")
			(pintype "passive")
		)
		(pad "K37" smd circle
			(at -20.956 -5.715 90)
			(size 0.64 0.64)
			(layers "F.Cu" "F.Mask")
			(net 225 "unconnected-(J18E-HB17_P_CC-PadK37)")
			(pinfunction "HB17_P_CC")
			(pintype "passive+no_connect")
		)
		(pad "K38" smd circle
			(at -22.226 -5.715 90)
			(size 0.64 0.64)
			(layers "F.Cu" "F.Mask")
			(net 226 "unconnected-(J18E-HB17_N_CC-PadK38)")
			(pinfunction "HB17_N_CC")
			(pintype "passive+no_connect")
		)
		(pad "K39" smd circle
			(at -23.497 -5.715 90)
			(size 0.64 0.64)
			(layers "F.Cu" "F.Mask")
			(net 1 "GND")
			(pinfunction "GND")
			(pintype "passive")
		)
		(pad "K40" smd circle
			(at -24.767 -5.715 90)
			(size 0.64 0.64)
			(layers "F.Cu" "F.Mask")
			(net 215 "unconnected-(J18A-VIO_B_M2C-PadJ39)")
			(pinfunction "VIO_B_M2C")
			(pintype "passive+no_connect")
		)
		(pad "L01" smd circle
			(at 24.765 -6.986 90)
			(size 0.64 0.64)
			(layers "F.Cu" "F.Mask")
			(net 227 "unconnected-(J18A-RES1-PadL01)")
			(pinfunction "RES1")
			(pintype "no_connect")
		)
		(pad "L02" smd circle
			(at 23.495 -6.986 90)
			(size 0.64 0.64)
			(layers "F.Cu" "F.Mask")
			(net 1 "GND")
			(pinfunction "GND")
			(pintype "passive")
		)
		(pad "L03" smd circle
			(at 22.225 -6.986 90)
			(size 0.64 0.64)
			(layers "F.Cu" "F.Mask")
			(net 1 "GND")
			(pinfunction "GND")
			(pintype "passive")
		)
		(pad "L04" smd circle
			(at 20.954 -6.986 90)
			(size 0.64 0.64)
			(layers "F.Cu" "F.Mask")
			(net 228 "unconnected-(J18G-GBTCLK4_M2C_P-PadL04)")
			(pinfunction "GBTCLK4_M2C_P")
			(pintype "passive+no_connect")
		)
		(pad "L05" smd circle
			(at 19.684 -6.986 90)
			(size 0.64 0.64)
			(layers "F.Cu" "F.Mask")
			(net 229 "unconnected-(J18G-GBTCLK4_M2C_N-PadL05)")
			(pinfunction "GBTCLK4_M2C_N")
			(pintype "passive+no_connect")
		)
		(pad "L06" smd circle
			(at 18.414 -6.986 90)
			(size 0.64 0.64)
			(layers "F.Cu" "F.Mask")
			(net 1 "GND")
			(pinfunction "GND")
			(pintype "passive")
		)
		(pad "L07" smd circle
			(at 17.144 -6.986 90)
			(size 0.64 0.64)
			(layers "F.Cu" "F.Mask")
			(net 1 "GND")
			(pinfunction "GND")
			(pintype "passive")
		)
		(pad "L08" smd circle
			(at 15.874 -6.986 90)
			(size 0.64 0.64)
			(layers "F.Cu" "F.Mask")
			(net 230 "unconnected-(J18G-GBTCLK3_M2C_P-PadL08)")
			(pinfunction "GBTCLK3_M2C_P")
			(pintype "passive+no_connect")
		)
		(pad "L09" smd circle
			(at 14.605 -6.986 90)
			(size 0.64 0.64)
			(layers "F.Cu" "F.Mask")
			(net 231 "unconnected-(J18G-GBTCLK3_M2C_N-PadL09)")
			(pinfunction "GBTCLK3_M2C_N")
			(pintype "passive+no_connect")
		)
		(pad "L10" smd circle
			(at 13.335 -6.986 90)
			(size 0.64 0.64)
			(layers "F.Cu" "F.Mask")
			(net 1 "GND")
			(pinfunction "GND")
			(pintype "passive")
		)
		(pad "L11" smd circle
			(at 12.063 -6.986 90)
			(size 0.64 0.64)
			(layers "F.Cu" "F.Mask")
			(net 1 "GND")
			(pinfunction "GND")
			(pintype "passive")
		)
		(pad "L12" smd circle
			(at 10.794 -6.986 90)
			(size 0.64 0.64)
			(layers "F.Cu" "F.Mask")
			(net 232 "unconnected-(J18G-GBTCLK2_M2C_P-PadL12)")
			(pinfunction "GBTCLK2_M2C_P")
			(pintype "passive+no_connect")
		)
		(pad "L13" smd circle
			(at 9.525 -6.986 90)
			(size 0.64 0.64)
			(layers "F.Cu" "F.Mask")
			(net 233 "unconnected-(J18G-GBTCLK2_M2C_N-PadL13)")
			(pinfunction "GBTCLK2_M2C_N")
			(pintype "passive+no_connect")
		)
		(pad "L14" smd circle
			(at 8.255 -6.986 90)
			(size 0.64 0.64)
			(layers "F.Cu" "F.Mask")
			(net 1 "GND")
			(pinfunction "GND")
			(pintype "passive")
		)
		(pad "L15" smd circle
			(at 6.985 -6.986 90)
			(size 0.64 0.64)
			(layers "F.Cu" "F.Mask")
			(net 1 "GND")
			(pinfunction "GND")
			(pintype "passive")
		)
		(pad "L16" smd circle
			(at 5.714 -6.986 90)
			(size 0.64 0.64)
			(layers "F.Cu" "F.Mask")
			(net 234 "unconnected-(J18G-SYNC_C2M_P-PadL16)")
			(pinfunction "SYNC_C2M_P")
			(pintype "passive+no_connect")
		)
		(pad "L17" smd circle
			(at 4.445 -6.986 90)
			(size 0.64 0.64)
			(layers "F.Cu" "F.Mask")
			(net 235 "unconnected-(J18G-SYNC_C2M_N-PadL17)")
			(pinfunction "SYNC_C2M_N")
			(pintype "passive+no_connect")
		)
		(pad "L18" smd circle
			(at 3.173 -6.986 90)
			(size 0.64 0.64)
			(layers "F.Cu" "F.Mask")
			(net 1 "GND")
			(pinfunction "GND")
			(pintype "passive")
		)
		(pad "L19" smd circle
			(at 1.904 -6.986 90)
			(size 0.64 0.64)
			(layers "F.Cu" "F.Mask")
			(net 1 "GND")
			(pinfunction "GND")
			(pintype "passive")
		)
		(pad "L20" smd circle
			(at 0.633 -6.986 90)
			(size 0.64 0.64)
			(layers "F.Cu" "F.Mask")
			(net 236 "unconnected-(J18G-REFCLK_C2M_P-PadL20)")
			(pinfunction "REFCLK_C2M_P")
			(pintype "passive+no_connect")
		)
		(pad "L21" smd circle
			(at -0.635 -6.986 90)
			(size 0.64 0.64)
			(layers "F.Cu" "F.Mask")
			(net 237 "unconnected-(J18G-REFCLK_C2M_N-PadL21)")
			(pinfunction "REFCLK_C2M_N")
			(pintype "passive+no_connect")
		)
		(pad "L22" smd circle
			(at -1.905 -6.986 90)
			(size 0.64 0.64)
			(layers "F.Cu" "F.Mask")
			(net 1 "GND")
			(pinfunction "GND")
			(pintype "passive")
		)
		(pad "L23" smd circle
			(at -3.176 -6.986 90)
			(size 0.64 0.64)
			(layers "F.Cu" "F.Mask")
			(net 1 "GND")
			(pinfunction "GND")
			(pintype "passive")
		)
		(pad "L24" smd circle
			(at -4.446 -6.986 90)
			(size 0.64 0.64)
			(layers "F.Cu" "F.Mask")
			(net 238 "unconnected-(J18G-REFCLK_M2C_P-PadL24)")
			(pinfunction "REFCLK_M2C_P")
			(pintype "passive+no_connect")
		)
		(pad "L25" smd circle
			(at -5.715 -6.986 90)
			(size 0.64 0.64)
			(layers "F.Cu" "F.Mask")
			(net 240 "unconnected-(J18G-REFCLK_M2C_N-PadL25)")
			(pinfunction "REFCLK_M2C_N")
			(pintype "passive+no_connect")
		)
		(pad "L26" smd circle
			(at -6.986 -6.986 90)
			(size 0.64 0.64)
			(layers "F.Cu" "F.Mask")
			(net 1 "GND")
			(pinfunction "GND")
			(pintype "passive")
		)
		(pad "L27" smd circle
			(at -8.257 -6.986 90)
			(size 0.64 0.64)
			(layers "F.Cu" "F.Mask")
			(net 1 "GND")
			(pinfunction "GND")
			(pintype "passive")
		)
		(pad "L28" smd circle
			(at -9.526 -6.986 90)
			(size 0.64 0.64)
			(layers "F.Cu" "F.Mask")
			(net 242 "unconnected-(J18G-SYNC_M2C_P-PadL28)")
			(pinfunction "SYNC_M2C_P")
			(pintype "passive+no_connect")
		)
		(pad "L29" smd circle
			(at -10.795 -6.986 90)
			(size 0.64 0.64)
			(layers "F.Cu" "F.Mask")
			(net 243 "unconnected-(J18G-SYNC_M2C_N-PadL29)")
			(pinfunction "SYNC_M2C_N")
			(pintype "passive+no_connect")
		)
		(pad "L30" smd circle
			(at -12.065 -6.986 90)
			(size 0.64 0.64)
			(layers "F.Cu" "F.Mask")
			(net 1 "GND")
			(pinfunction "GND")
			(pintype "passive")
		)
		(pad "L31" smd circle
			(at -13.337 -6.986 90)
			(size 0.64 0.64)
			(layers "F.Cu" "F.Mask")
			(net 1 "GND")
			(pinfunction "GND")
			(pintype "passive")
		)
		(pad "L32" smd circle
			(at -14.606 -6.986 90)
			(size 0.64 0.64)
			(layers "F.Cu" "F.Mask")
			(net 244 "unconnected-(J18A-RES2-PadL32)")
			(pinfunction "RES2")
			(pintype "no_connect")
		)
		(pad "L33" smd circle
			(at -15.875 -6.986 90)
			(size 0.64 0.64)
			(layers "F.Cu" "F.Mask")
			(net 245 "unconnected-(J18A-RES3-PadL33)")
			(pinfunction "RES3")
			(pintype "no_connect")
		)
		(pad "L34" smd circle
			(at -17.145 -6.986 90)
			(size 0.64 0.64)
			(layers "F.Cu" "F.Mask")
			(net 1 "GND")
			(pinfunction "GND")
			(pintype "passive")
		)
		(pad "L35" smd circle
			(at -18.415 -6.986 90)
			(size 0.64 0.64)
			(layers "F.Cu" "F.Mask")
			(net 1 "GND")
			(pinfunction "GND")
			(pintype "passive")
		)
		(pad "L36" smd circle
			(at -19.685 -6.986 90)
			(size 0.64 0.64)
			(layers "F.Cu" "F.Mask")
			(net 59 "12P0V")
			(pinfunction "12P0V")
			(pintype "passive")
		)
		(pad "L37" smd circle
			(at -20.956 -6.986 90)
			(size 0.64 0.64)
			(layers "F.Cu" "F.Mask")
			(net 59 "12P0V")
			(pinfunction "12P0V")
			(pintype "passive")
		)
		(pad "L38" smd circle
			(at -22.226 -6.986 90)
			(size 0.64 0.64)
			(layers "F.Cu" "F.Mask")
			(net 1 "GND")
			(pinfunction "GND")
			(pintype "passive")
		)
		(pad "L39" smd circle
			(at -23.497 -6.986 90)
			(size 0.64 0.64)
			(layers "F.Cu" "F.Mask")
			(net 1 "GND")
			(pinfunction "GND")
			(pintype "passive")
		)
		(pad "L40" smd circle
			(at -24.767 -6.986 90)
			(size 0.64 0.64)
			(layers "F.Cu" "F.Mask")
			(net 59 "12P0V")
			(pinfunction "12P0V")
			(pintype "passive")
		)
		(pad "M01" smd circle
			(at 24.765 -8.257 90)
			(size 0.64 0.64)
			(layers "F.Cu" "F.Mask")
			(net 1 "GND")
			(pinfunction "GND")
			(pintype "passive")
		)
		(pad "M02" smd circle
			(at 23.495 -8.257 90)
			(size 0.64 0.64)
			(layers "F.Cu" "F.Mask")
			(net 247 "unconnected-(J18H-DP23_M2C_P-PadM02)")
			(pinfunction "DP23_M2C_P")
			(pintype "passive+no_connect")
		)
	)
)
